(kicad_pcb
	(version 20260206)
	(generator "pcbnew")
	(generator_version "10.0")
	(general
		(thickness 1.6)
		(legacy_teardrops no)
	)
	(paper "A4")
	(title_block
		(title "panther-plus-userver — 13130-1b_20150205.brd")
		(comment 1 "Honey Badger (Wiwynn) / footprints 1218-1225 of 1509")
	)
	(layers
		(0 "F.Cu" signal "TOP")
		(4 "In1.Cu" signal "L2")
		(6 "In2.Cu" signal "L3")
		(8 "In3.Cu" signal "L4")
		(10 "In4.Cu" signal "L5")
		(12 "In5.Cu" signal "L6")
		(14 "In6.Cu" signal "L7")
		(16 "In7.Cu" signal "L8")
		(18 "In8.Cu" signal "L9")
		(20 "In9.Cu" signal "L10")
		(22 "In10.Cu" signal "L11")
		(2 "B.Cu" signal "BOTTOM")
		(9 "F.Adhes" user "F.Adhesive")
		(11 "B.Adhes" user "B.Adhesive")
		(13 "F.Paste" user "Package Geometry/Pastemask Top")
		(15 "B.Paste" user "Package Geometry/Pastemask Bottom")
		(5 "F.SilkS" user "Ref Des/Silkscreen Top")
		(7 "B.SilkS" user "Ref Des/Silkscreen Bottom")
		(1 "F.Mask" user "Board Geometry/Soldermask Top")
		(3 "B.Mask" user "Board Geometry/Soldermask Bottom")
		(17 "Dwgs.User" user "User.Drawings")
		(19 "Cmts.User" user "User.Comments")
		(21 "Eco1.User" user "User.Eco1")
		(23 "Eco2.User" user "User.Eco2")
		(25 "Edge.Cuts" user "Board Geometry/Outline")
		(27 "Margin" user)
		(31 "F.CrtYd" user "Package Geometry/Place Bound Top")
		(29 "B.CrtYd" user "Package Geometry/Place Bound Bottom")
		(35 "F.Fab" user "Ref Des/Assembly Top")
		(33 "B.Fab" user "Ref Des/Assembly Bottom")
	)
	(footprint ""
		(layer "B.Cu")
		(at 92.5322 -40.9829 180)
		(property "Reference" "C167"
			(at 0 0 0)
			(layer "B.SilkS")
			(hide yes)
			(effects
				(font
					(size 1.27 1.27)
				)
				(justify mirror)
			)
		)
		(property "Value" "SC1U10V2KX-1GP"
			(at -1.1811 -2.7051 180)
			(unlocked yes)
			(layer "B.Fab")
			(hide yes)
			(effects
				(font
					(size 1.016 1.016)
					(thickness 0.1524)
				)
				(justify mirror)
			)
		)
		(property "Device Type" "C402H22"
			(at -1.1811 -4.2291 180)
			(unlocked yes)
			(layer "B.Fab")
			(hide yes)
			(effects
				(font
					(size 1.016 1.016)
					(thickness 0.1524)
				)
				(justify mirror)
			)
		)
		(duplicate_pad_numbers_are_jumpers no)
		(fp_rect
			(start 0.381 0.7366)
			(end -0.381 -0.7366)
			(stroke
				(width 0)
				(type default)
			)
			(fill no)
			(layer "B.CrtYd")
		)
		(fp_rect
			(start 0.381 0.7366)
			(end -0.381 -0.7366)
			(stroke
				(width 0)
				(type default)
			)
			(fill no)
			(layer "B.Fab")
		)
		(pad "1" smd custom
			(at 0 -0.4572)
			(size 0.1143 0.1143)
			(layers "B.Cu" "B.Mask" "B.Paste")
			(net "PVNN")
			(options
				(clearance outline)
				(anchor circle)
			)
			(primitives
				(gr_poly
					(pts
						(arc
							(start -0.254 0.1778)
							(mid -0.239121 0.213721)
							(end -0.2032 0.2286)
						)
						(arc
							(start 0.2032 0.2286)
							(mid 0.239121 0.213721)
							(end 0.254 0.1778)
						)
						(arc
							(start 0.254 -0.1778)
							(mid 0.239121 -0.213721)
							(end 0.2032 -0.2286)
						)
						(arc
							(start -0.2032 -0.2286)
							(mid -0.239121 -0.213721)
							(end -0.254 -0.1778)
						)
					)
					(width 0)
					(fill yes)
				)
			)
		)
		(pad "2" smd custom
			(at 0 0.4572)
			(size 0.1143 0.1143)
			(layers "B.Cu" "B.Mask" "B.Paste")
			(net "GND")
			(options
				(clearance outline)
				(anchor circle)
			)
			(primitives
				(gr_poly
					(pts
						(arc
							(start -0.254 0.1778)
							(mid -0.239121 0.213721)
							(end -0.2032 0.2286)
						)
						(arc
							(start 0.2032 0.2286)
							(mid 0.239121 0.213721)
							(end 0.254 0.1778)
						)
						(arc
							(start 0.254 -0.1778)
							(mid 0.239121 -0.213721)
							(end 0.2032 -0.2286)
						)
						(arc
							(start -0.2032 -0.2286)
							(mid -0.239121 -0.213721)
							(end -0.254 -0.1778)
						)
					)
					(width 0)
					(fill yes)
				)
			)
		)
	)
	(footprint ""
		(layer "B.Cu")
		(at 44.6024 -28.321 180)
		(property "Reference" "R446"
			(at 0 0 0)
			(layer "B.SilkS")
			(hide yes)
			(effects
				(font
					(size 1.27 1.27)
				)
				(justify mirror)
			)
		)
		(property "Value" "4K7R2F-GP"
			(at -1.7907 -1.1176 180)
			(unlocked yes)
			(layer "B.Fab")
			(hide yes)
			(effects
				(font
					(size 1.016 1.016)
					(thickness 0.1524)
				)
				(justify mirror)
			)
		)
		(property "Device Type" "R402H16"
			(at -1.7907 -2.6416 180)
			(unlocked yes)
			(layer "B.Fab")
			(hide yes)
			(effects
				(font
					(size 1.016 1.016)
					(thickness 0.1524)
				)
				(justify mirror)
			)
		)
		(duplicate_pad_numbers_are_jumpers no)
		(fp_rect
			(start 0.381 0.8382)
			(end -0.381 -0.8382)
			(stroke
				(width 0)
				(type default)
			)
			(fill no)
			(layer "B.CrtYd")
		)
		(fp_rect
			(start 0.381 0.8382)
			(end -0.381 -0.8382)
			(stroke
				(width 0)
				(type default)
			)
			(fill no)
			(layer "B.Fab")
		)
		(pad "1" smd custom
			(at 0 -0.4318)
			(size 0.127 0.127)
			(layers "B.Cu" "B.Mask" "B.Paste")
			(net "CLKBUFF_OE5#")
			(options
				(clearance outline)
				(anchor circle)
			)
			(primitives
				(gr_poly
					(pts
						(arc
							(start -0.2032 0.2794)
							(mid -0.239121 0.264521)
							(end -0.254 0.2286)
						)
						(arc
							(start -0.254 -0.2286)
							(mid -0.239121 -0.264521)
							(end -0.2032 -0.2794)
						)
						(arc
							(start 0.2032 -0.2794)
							(mid 0.239121 -0.264521)
							(end 0.254 -0.2286)
						)
						(arc
							(start 0.254 0.2286)
							(mid 0.239121 0.264521)
							(end 0.2032 0.2794)
						)
					)
					(width 0)
					(fill yes)
				)
			)
		)
		(pad "2" smd custom
			(at 0 0.4318)
			(size 0.127 0.127)
			(layers "B.Cu" "B.Mask" "B.Paste")
			(net "GND")
			(options
				(clearance outline)
				(anchor circle)
			)
			(primitives
				(gr_poly
					(pts
						(arc
							(start -0.2032 0.2794)
							(mid -0.239121 0.264521)
							(end -0.254 0.2286)
						)
						(arc
							(start -0.254 -0.2286)
							(mid -0.239121 -0.264521)
							(end -0.2032 -0.2794)
						)
						(arc
							(start 0.2032 -0.2794)
							(mid 0.239121 -0.264521)
							(end 0.254 -0.2286)
						)
						(arc
							(start 0.254 0.2286)
							(mid 0.239121 0.264521)
							(end 0.2032 0.2794)
						)
					)
					(width 0)
					(fill yes)
				)
			)
		)
	)
	(footprint ""
		(layer "B.Cu")
		(at 160.8582 -12.447778 180)
		(property "Reference" "C334"
			(at 0 0 0)
			(layer "B.SilkS")
			(hide yes)
			(effects
				(font
					(size 1.27 1.27)
				)
				(justify mirror)
			)
		)
		(property "Value" "SCD1U16V2KX-3GP"
			(at -1.8923 -1.2065 180)
			(unlocked yes)
			(layer "B.Fab")
			(hide yes)
			(effects
				(font
					(size 1.016 1.016)
					(thickness 0.1524)
				)
				(justify mirror)
			)
		)
		(property "Device Type" "C402H22"
			(at -1.8923 -2.7305 180)
			(unlocked yes)
			(layer "B.Fab")
			(hide yes)
			(effects
				(font
					(size 1.016 1.016)
					(thickness 0.1524)
				)
				(justify mirror)
			)
		)
		(duplicate_pad_numbers_are_jumpers no)
		(fp_rect
			(start 0.381 0.7366)
			(end -0.381 -0.7366)
			(stroke
				(width 0)
				(type default)
			)
			(fill no)
			(layer "B.CrtYd")
		)
		(fp_rect
			(start 0.381 0.7366)
			(end -0.381 -0.7366)
			(stroke
				(width 0)
				(type default)
			)
			(fill no)
			(layer "B.Fab")
		)
		(pad "1" smd custom
			(at 0 -0.4572)
			(size 0.1143 0.1143)
			(layers "B.Cu" "B.Mask" "B.Paste")
			(net "PV_VDDR")
			(options
				(clearance outline)
				(anchor circle)
			)
			(primitives
				(gr_poly
					(pts
						(arc
							(start -0.254 0.1778)
							(mid -0.239121 0.213721)
							(end -0.2032 0.2286)
						)
						(arc
							(start 0.2032 0.2286)
							(mid 0.239121 0.213721)
							(end 0.254 0.1778)
						)
						(arc
							(start 0.254 -0.1778)
							(mid 0.239121 -0.213721)
							(end 0.2032 -0.2286)
						)
						(arc
							(start -0.2032 -0.2286)
							(mid -0.239121 -0.213721)
							(end -0.254 -0.1778)
						)
					)
					(width 0)
					(fill yes)
				)
			)
		)
		(pad "2" smd custom
			(at 0 0.4572)
			(size 0.1143 0.1143)
			(layers "B.Cu" "B.Mask" "B.Paste")
			(net "GND")
			(options
				(clearance outline)
				(anchor circle)
			)
			(primitives
				(gr_poly
					(pts
						(arc
							(start -0.254 0.1778)
							(mid -0.239121 0.213721)
							(end -0.2032 0.2286)
						)
						(arc
							(start 0.2032 0.2286)
							(mid 0.239121 0.213721)
							(end 0.254 0.1778)
						)
						(arc
							(start 0.254 -0.1778)
							(mid 0.239121 -0.213721)
							(end 0.2032 -0.2286)
						)
						(arc
							(start -0.2032 -0.2286)
							(mid -0.239121 -0.213721)
							(end -0.254 -0.1778)
						)
					)
					(width 0)
					(fill yes)
				)
			)
		)
	)
	(footprint ""
		(layer "B.Cu")
		(at 40.6654 -47.117)
		(property "Reference" "C61"
			(at 0 0 0)
			(layer "B.SilkS")
			(hide yes)
			(effects
				(font
					(size 1.27 1.27)
				)
				(justify mirror)
			)
		)
		(property "Value" "SCD1U10V2KX-5GP"
			(at -1.8923 -1.2065 0)
			(unlocked yes)
			(layer "B.Fab")
			(hide yes)
			(effects
				(font
					(size 1.016 1.016)
					(thickness 0.1524)
				)
				(justify mirror)
			)
		)
		(property "Device Type" "C402H22"
			(at -1.8923 -2.7305 0)
			(unlocked yes)
			(layer "B.Fab")
			(hide yes)
			(effects
				(font
					(size 1.016 1.016)
					(thickness 0.1524)
				)
				(justify mirror)
			)
		)
		(duplicate_pad_numbers_are_jumpers no)
		(fp_rect
			(start 0.381 0.7366)
			(end -0.381 -0.7366)
			(stroke
				(width 0)
				(type default)
			)
			(fill no)
			(layer "B.CrtYd")
		)
		(fp_rect
			(start 0.381 0.7366)
			(end -0.381 -0.7366)
			(stroke
				(width 0)
				(type default)
			)
			(fill no)
			(layer "B.Fab")
		)
		(pad "1" smd custom
			(at 0 -0.4572 180)
			(size 0.1143 0.1143)
			(layers "B.Cu" "B.Mask" "B.Paste")
			(net "P3V3_CLK_XTAL")
			(options
				(clearance outline)
				(anchor circle)
			)
			(primitives
				(gr_poly
					(pts
						(arc
							(start -0.254 0.1778)
							(mid -0.239121 0.213721)
							(end -0.2032 0.2286)
						)
						(arc
							(start 0.2032 0.2286)
							(mid 0.239121 0.213721)
							(end 0.254 0.1778)
						)
						(arc
							(start 0.254 -0.1778)
							(mid 0.239121 -0.213721)
							(end 0.2032 -0.2286)
						)
						(arc
							(start -0.2032 -0.2286)
							(mid -0.239121 -0.213721)
							(end -0.254 -0.1778)
						)
					)
					(width 0)
					(fill yes)
				)
			)
		)
		(pad "2" smd custom
			(at 0 0.4572 180)
			(size 0.1143 0.1143)
			(layers "B.Cu" "B.Mask" "B.Paste")
			(net "GND")
			(options
				(clearance outline)
				(anchor circle)
			)
			(primitives
				(gr_poly
					(pts
						(arc
							(start -0.254 0.1778)
							(mid -0.239121 0.213721)
							(end -0.2032 0.2286)
						)
						(arc
							(start 0.2032 0.2286)
							(mid 0.239121 0.213721)
							(end 0.254 0.1778)
						)
						(arc
							(start 0.254 -0.1778)
							(mid 0.239121 -0.213721)
							(end 0.2032 -0.2286)
						)
						(arc
							(start -0.2032 -0.2286)
							(mid -0.239121 -0.213721)
							(end -0.254 -0.1778)
						)
					)
					(width 0)
					(fill yes)
				)
			)
		)
	)
	(footprint ""
		(layer "B.Cu")
		(at 186.563 -26.797 90)
		(property "Reference" "PR210"
			(at 0 0 90)
			(layer "B.SilkS")
			(hide yes)
			(effects
				(font
					(size 1.27 1.27)
				)
				(justify mirror)
			)
		)
		(property "Value" "11KR2F-L-GP"
			(at -1.7907 -1.1176 90)
			(unlocked yes)
			(layer "B.Fab")
			(hide yes)
			(effects
				(font
					(size 1.016 1.016)
					(thickness 0.1524)
				)
				(justify mirror)
			)
		)
		(property "Device Type" "R402H16"
			(at -1.7907 -2.6416 90)
			(unlocked yes)
			(layer "B.Fab")
			(hide yes)
			(effects
				(font
					(size 1.016 1.016)
					(thickness 0.1524)
				)
				(justify mirror)
			)
		)
		(duplicate_pad_numbers_are_jumpers no)
		(fp_rect
			(start 0.381 0.8382)
			(end -0.381 -0.8382)
			(stroke
				(width 0)
				(type default)
			)
			(fill no)
			(layer "B.CrtYd")
		)
		(fp_rect
			(start 0.381 0.8382)
			(end -0.381 -0.8382)
			(stroke
				(width 0)
				(type default)
			)
			(fill no)
			(layer "B.Fab")
		)
		(pad "1" smd custom
			(at 0 -0.4318 270)
			(size 0.127 0.127)
			(layers "B.Cu" "B.Mask" "B.Paste")
			(net "VR_PVDDRA_ISUMP1")
			(options
				(clearance outline)
				(anchor circle)
			)
			(primitives
				(gr_poly
					(pts
						(arc
							(start -0.2032 0.2794)
							(mid -0.239121 0.264521)
							(end -0.254 0.2286)
						)
						(arc
							(start -0.254 -0.2286)
							(mid -0.239121 -0.264521)
							(end -0.2032 -0.2794)
						)
						(arc
							(start 0.2032 -0.2794)
							(mid 0.239121 -0.264521)
							(end 0.254 -0.2286)
						)
						(arc
							(start 0.254 0.2286)
							(mid 0.239121 0.264521)
							(end 0.2032 0.2794)
						)
					)
					(width 0)
					(fill yes)
				)
			)
		)
		(pad "2" smd custom
			(at 0 0.4318 270)
			(size 0.127 0.127)
			(layers "B.Cu" "B.Mask" "B.Paste")
			(net "VR_PVDDRA_ISUMN1")
			(options
				(clearance outline)
				(anchor circle)
			)
			(primitives
				(gr_poly
					(pts
						(arc
							(start -0.2032 0.2794)
							(mid -0.239121 0.264521)
							(end -0.254 0.2286)
						)
						(arc
							(start -0.254 -0.2286)
							(mid -0.239121 -0.264521)
							(end -0.2032 -0.2794)
						)
						(arc
							(start 0.2032 -0.2794)
							(mid 0.239121 -0.264521)
							(end 0.254 -0.2286)
						)
						(arc
							(start 0.254 0.2286)
							(mid 0.239121 0.264521)
							(end 0.2032 0.2794)
						)
					)
					(width 0)
					(fill yes)
				)
			)
		)
	)
	(footprint ""
		(layer "B.Cu")
		(at 146.05 -23.495 -90)
		(property "Reference" "R104"
			(at 0 0 90)
			(layer "B.SilkS")
			(hide yes)
			(effects
				(font
					(size 1.27 1.27)
				)
				(justify mirror)
			)
		)
		(property "Value" "0R2J-2-GP"
			(at -0.064008 -3.993896 270)
			(unlocked yes)
			(layer "B.Fab")
			(hide yes)
			(effects
				(font
					(size 1.016 1.016)
					(thickness 0.1524)
				)
				(justify mirror)
			)
		)
		(property "Device Type" "R402H16"
			(at -0.064008 -5.517896 270)
			(unlocked yes)
			(layer "B.Fab")
			(hide yes)
			(effects
				(font
					(size 1.016 1.016)
					(thickness 0.1524)
				)
				(justify mirror)
			)
		)
		(duplicate_pad_numbers_are_jumpers no)
		(fp_rect
			(start 0.381 0.8382)
			(end -0.381 -0.8382)
			(stroke
				(width 0)
				(type default)
			)
			(fill no)
			(layer "B.CrtYd")
		)
		(fp_rect
			(start 0.381 0.8382)
			(end -0.381 -0.8382)
			(stroke
				(width 0)
				(type default)
			)
			(fill no)
			(layer "B.Fab")
		)
		(pad "1" smd custom
			(at 0 -0.4318 90)
			(size 0.127 0.127)
			(layers "B.Cu" "B.Mask" "B.Paste")
			(net "MSEL2")
			(options
				(clearance outline)
				(anchor circle)
			)
			(primitives
				(gr_poly
					(pts
						(arc
							(start -0.2032 0.2794)
							(mid -0.239121 0.264521)
							(end -0.254 0.2286)
						)
						(arc
							(start -0.254 -0.2286)
							(mid -0.239121 -0.264521)
							(end -0.2032 -0.2794)
						)
						(arc
							(start 0.2032 -0.2794)
							(mid 0.239121 -0.264521)
							(end 0.254 -0.2286)
						)
						(arc
							(start 0.254 0.2286)
							(mid 0.239121 0.264521)
							(end 0.2032 0.2794)
						)
					)
					(width 0)
					(fill yes)
				)
			)
		)
		(pad "2" smd custom
			(at 0 0.4318 90)
			(size 0.127 0.127)
			(layers "B.Cu" "B.Mask" "B.Paste")
			(net "GND")
			(options
				(clearance outline)
				(anchor circle)
			)
			(primitives
				(gr_poly
					(pts
						(arc
							(start -0.2032 0.2794)
							(mid -0.239121 0.264521)
							(end -0.254 0.2286)
						)
						(arc
							(start -0.254 -0.2286)
							(mid -0.239121 -0.264521)
							(end -0.2032 -0.2794)
						)
						(arc
							(start 0.2032 -0.2794)
							(mid 0.239121 -0.264521)
							(end 0.254 -0.2286)
						)
						(arc
							(start 0.254 0.2286)
							(mid 0.239121 0.264521)
							(end 0.2032 0.2794)
						)
					)
					(width 0)
					(fill yes)
				)
			)
		)
	)
	(footprint ""
		(layer "B.Cu")
		(at 87.757 -42.291)
		(property "Reference" "TP66"
			(at 0 0 0)
			(layer "B.SilkS")
			(hide yes)
			(effects
				(font
					(size 1.27 1.27)
				)
				(justify mirror)
			)
		)
		(property "Value" "TPAD28-1-GP-U"
			(at -0.0508 -1.9304 0)
			(unlocked yes)
			(layer "B.Fab")
			(hide yes)
			(effects
				(font
					(size 1.016 1.016)
					(thickness 0.1524)
				)
				(justify mirror)
			)
		)
		(property "Device Type" "TPAD28-1-U"
			(at -0.0508 -3.4544 0)
			(unlocked yes)
			(layer "B.Fab")
			(hide yes)
			(effects
				(font
					(size 1.016 1.016)
					(thickness 0.1524)
				)
				(justify mirror)
			)
		)
		(duplicate_pad_numbers_are_jumpers no)
		(fp_poly
			(pts
				(arc
					(start 0.3556 0)
					(mid -0.3556 0)
					(end 0.3556 0)
				)
			)
			(stroke
				(width 0)
				(type default)
			)
			(fill no)
			(layer "B.CrtYd")
		)
		(fp_poly
			(pts
				(arc
					(start 0.9525 0)
					(mid -0.9525 0)
					(end 0.9525 0)
				)
			)
			(stroke
				(width 0)
				(type default)
			)
			(fill no)
			(layer "B.Fab")
		)
		(pad "1" smd circle
			(at 0 0 180)
			(size 0.7112 0.7112)
			(layers "B.Cu" "B.Mask" "B.Paste")
			(net "LPC_CPU_R_CLKOUT1")
		)
	)
	(footprint ""
		(layer "B.Cu")
		(at 70.358 -12.954)
		(property "Reference" "R479"
			(at 0 0 0)
			(layer "B.SilkS")
			(hide yes)
			(effects
				(font
					(size 1.27 1.27)
				)
				(justify mirror)
			)
		)
		(property "Value" "4K7R2F-GP"
			(at -1.7907 -1.1176 0)
			(unlocked yes)
			(layer "B.Fab")
			(hide yes)
			(effects
				(font
					(size 1.016 1.016)
					(thickness 0.1524)
				)
				(justify mirror)
			)
		)
		(property "Device Type" "R402H16"
			(at -1.7907 -2.6416 0)
			(unlocked yes)
			(layer "B.Fab")
			(hide yes)
			(effects
				(font
					(size 1.016 1.016)
					(thickness 0.1524)
				)
				(justify mirror)
			)
		)
		(duplicate_pad_numbers_are_jumpers no)
		(fp_rect
			(start 0.381 0.8382)
			(end -0.381 -0.8382)
			(stroke
				(width 0)
				(type default)
			)
			(fill no)
			(layer "B.CrtYd")
		)
		(fp_rect
			(start 0.381 0.8382)
			(end -0.381 -0.8382)
			(stroke
				(width 0)
				(type default)
			)
			(fill no)
			(layer "B.Fab")
		)
		(pad "1" smd custom
			(at 0 -0.4318 180)
			(size 0.127 0.127)
			(layers "B.Cu" "B.Mask" "B.Paste")
			(net "P3V3")
			(options
				(clearance outline)
				(anchor circle)
			)
			(primitives
				(gr_poly
					(pts
						(arc
							(start -0.2032 0.2794)
							(mid -0.239121 0.264521)
							(end -0.254 0.2286)
						)
						(arc
							(start -0.254 -0.2286)
							(mid -0.239121 -0.264521)
							(end -0.2032 -0.2794)
						)
						(arc
							(start 0.2032 -0.2794)
							(mid 0.239121 -0.264521)
							(end 0.254 -0.2286)
						)
						(arc
							(start 0.254 0.2286)
							(mid 0.239121 0.264521)
							(end 0.2032 0.2794)
						)
					)
					(width 0)
					(fill yes)
				)
			)
		)
		(pad "2" smd custom
			(at 0 0.4318 180)
			(size 0.127 0.127)
			(layers "B.Cu" "B.Mask" "B.Paste")
			(net "BMC_SYS_RESET#")
			(options
				(clearance outline)
				(anchor circle)
			)
			(primitives
				(gr_poly
					(pts
						(arc
							(start -0.2032 0.2794)
							(mid -0.239121 0.264521)
							(end -0.254 0.2286)
						)
						(arc
							(start -0.254 -0.2286)
							(mid -0.239121 -0.264521)
							(end -0.2032 -0.2794)
						)
						(arc
							(start 0.2032 -0.2794)
							(mid 0.239121 -0.264521)
							(end 0.254 -0.2286)
						)
						(arc
							(start 0.254 0.2286)
							(mid 0.239121 0.264521)
							(end 0.2032 0.2794)
						)
					)
					(width 0)
					(fill yes)
				)
			)
		)
	)
)
